(kicad_pcb
	(version 20260206)
	(generator "pcbnew")
	(generator_version "10.0")
	(general
		(thickness 1.6)
		(legacy_teardrops no)
	)
	(paper "A4")
	(title_block
		(title "9052_F0T_PDB_Converter_Brick_F_V03_1208_1600_OCP.brd")
		(comment 1 "Grand Teton / footprints 271-278 of 578")
	)
	(layers
		(0 "F.Cu" signal "TOP")
		(4 "In1.Cu" signal "GND")
		(6 "In2.Cu" signal "IN1")
		(8 "In3.Cu" signal "GND1")
		(10 "In4.Cu" signal "VCC")
		(12 "In5.Cu" signal "VCC1")
		(14 "In6.Cu" signal "GND2")
		(16 "In7.Cu" signal "IN2")
		(18 "In8.Cu" signal "GND3")
		(2 "B.Cu" signal "BOTTOM")
		(9 "F.Adhes" user "F.Adhesive")
		(11 "B.Adhes" user "B.Adhesive")
		(13 "F.Paste" user "Package Geometry/Pastemask Top")
		(15 "B.Paste" user "Package Geometry/Pastemask Bottom")
		(5 "F.SilkS" user "Ref Des/Silkscreen Top")
		(7 "B.SilkS" user "Ref Des/Silkscreen Bottom")
		(1 "F.Mask" user "Board Geometry/Soldermask Top")
		(3 "B.Mask" user "Board Geometry/Soldermask Bottom")
		(17 "Dwgs.User" user "User.Drawings")
		(19 "Cmts.User" user "User.Comments")
		(21 "Eco1.User" user "User.Eco1")
		(23 "Eco2.User" user "User.Eco2")
		(25 "Edge.Cuts" user "Board Geometry/Outline")
		(27 "Margin" user)
		(31 "F.CrtYd" user "Package Geometry/Place Bound Top")
		(29 "B.CrtYd" user "Package Geometry/Place Bound Bottom")
		(35 "F.Fab" user "Ref Des/Assembly Top")
		(33 "B.Fab" user "Ref Des/Assembly Bottom")
	)
	(footprint ""
		(layer "F.Cu")
		(at 60.452 -61.722)
		(property "Reference" "PC85"
			(at 0 0 0)
			(layer "F.SilkS")
			(hide yes)
			(effects
				(font
					(size 1.27 1.27)
				)
			)
		)
		(property "Value" ""
			(at 0 0 0)
			(layer "F.Fab")
			(effects
				(font
					(size 1.27 1.27)
				)
			)
		)
		(duplicate_pad_numbers_are_jumpers no)
		(fp_line
			(start -0.7874 -0.4064)
			(end 0.7874 -0.4064)
			(stroke
				(width 0.1524)
				(type default)
			)
			(layer "F.SilkS")
		)
		(fp_line
			(start -0.7874 0.4064)
			(end -0.7874 -0.4064)
			(stroke
				(width 0.1524)
				(type default)
			)
			(layer "F.SilkS")
		)
		(fp_line
			(start 0.7874 -0.4064)
			(end 0.7874 0.4064)
			(stroke
				(width 0.1524)
				(type default)
			)
			(layer "F.SilkS")
		)
		(fp_line
			(start 0.7874 0.4064)
			(end -0.7874 0.4064)
			(stroke
				(width 0.1524)
				(type default)
			)
			(layer "F.SilkS")
		)
		(fp_line
			(start -0.6858 -0.3048)
			(end -0.1016 -0.3048)
			(stroke
				(width 0.1)
				(type default)
			)
			(layer "F.Fab")
		)
		(fp_line
			(start -0.6858 0.3048)
			(end -0.6858 -0.3048)
			(stroke
				(width 0.1)
				(type default)
			)
			(layer "F.Fab")
		)
		(fp_line
			(start -0.1016 -0.3048)
			(end -0.1016 -0.2794)
			(stroke
				(width 0.1)
				(type default)
			)
			(layer "F.Fab")
		)
		(fp_line
			(start -0.1016 -0.2794)
			(end 0.1016 -0.2794)
			(stroke
				(width 0.1)
				(type default)
			)
			(layer "F.Fab")
		)
		(fp_line
			(start -0.1016 0.2794)
			(end -0.1016 0.3048)
			(stroke
				(width 0.1)
				(type default)
			)
			(layer "F.Fab")
		)
		(fp_line
			(start -0.1016 0.3048)
			(end -0.6858 0.3048)
			(stroke
				(width 0.1)
				(type default)
			)
			(layer "F.Fab")
		)
		(fp_line
			(start 0.1016 -0.3048)
			(end 0.6858 -0.3048)
			(stroke
				(width 0.1)
				(type default)
			)
			(layer "F.Fab")
		)
		(fp_line
			(start 0.1016 -0.2794)
			(end 0.1016 -0.3048)
			(stroke
				(width 0.1)
				(type default)
			)
			(layer "F.Fab")
		)
		(fp_line
			(start 0.1016 0.2794)
			(end -0.1016 0.2794)
			(stroke
				(width 0.1)
				(type default)
			)
			(layer "F.Fab")
		)
		(fp_line
			(start 0.1016 0.3048)
			(end 0.1016 0.2794)
			(stroke
				(width 0.1)
				(type default)
			)
			(layer "F.Fab")
		)
		(fp_line
			(start 0.6858 -0.3048)
			(end 0.6858 0.3048)
			(stroke
				(width 0.1)
				(type default)
			)
			(layer "F.Fab")
		)
		(fp_line
			(start 0.6858 0.3048)
			(end 0.1016 0.3048)
			(stroke
				(width 0.1)
				(type default)
			)
			(layer "F.Fab")
		)
		(pad "1" smd rect
			(at -0.40005 0 180)
			(size 0.4572 0.508)
			(layers "F.Cu" "F.Mask" "F.Paste")
			(net "P12V_BRICK")
		)
		(pad "2" smd rect
			(at 0.40005 0 180)
			(size 0.4572 0.508)
			(layers "F.Cu" "F.Mask" "F.Paste")
			(net "GND")
		)
	)
	(footprint ""
		(layer "F.Cu")
		(at 84.582 -51.943)
		(property "Reference" "PC90"
			(at 0 0 0)
			(layer "F.SilkS")
			(hide yes)
			(effects
				(font
					(size 1.27 1.27)
				)
			)
		)
		(property "Value" ""
			(at 0 0 0)
			(layer "F.Fab")
			(effects
				(font
					(size 1.27 1.27)
				)
			)
		)
		(duplicate_pad_numbers_are_jumpers no)
		(fp_line
			(start -1.524 -0.762)
			(end 1.524 -0.762)
			(stroke
				(width 0.1524)
				(type default)
			)
			(layer "F.SilkS")
		)
		(fp_line
			(start -1.524 0.762)
			(end -1.524 -0.762)
			(stroke
				(width 0.1524)
				(type default)
			)
			(layer "F.SilkS")
		)
		(fp_line
			(start 1.524 -0.762)
			(end 1.524 0.762)
			(stroke
				(width 0.1524)
				(type default)
			)
			(layer "F.SilkS")
		)
		(fp_line
			(start 1.524 0.762)
			(end -1.524 0.762)
			(stroke
				(width 0.1524)
				(type default)
			)
			(layer "F.SilkS")
		)
		(fp_line
			(start -1.1049 -0.724916)
			(end -1.1049 0.724916)
			(stroke
				(width 0.1)
				(type default)
			)
			(layer "F.Fab")
		)
		(fp_line
			(start -1.1049 0.724916)
			(end 1.1049 0.724916)
			(stroke
				(width 0.1)
				(type default)
			)
			(layer "F.Fab")
		)
		(fp_line
			(start 1.1049 -0.724916)
			(end -1.1049 -0.724916)
			(stroke
				(width 0.1)
				(type default)
			)
			(layer "F.Fab")
		)
		(fp_line
			(start 1.1049 0.724916)
			(end 1.1049 -0.724916)
			(stroke
				(width 0.1)
				(type default)
			)
			(layer "F.Fab")
		)
		(pad "1" smd rect
			(at -0.889 0 180)
			(size 1.016 1.27)
			(layers "F.Cu" "F.Mask" "F.Paste")
			(net "P12V_BRICK")
		)
		(pad "2" smd rect
			(at 0.889 0 180)
			(size 1.016 1.27)
			(layers "F.Cu" "F.Mask" "F.Paste")
			(net "GND")
		)
	)
	(footprint ""
		(layer "F.Cu")
		(at 224.259394 -130.31978 180)
		(property "Reference" "L3"
			(at -5.568442 -7.377176 0)
			(unlocked yes)
			(layer "F.SilkS")
			(effects
				(font
					(size 0.7874 0.5842)
					(thickness 0.1524)
				)
				(justify left)
			)
		)
		(property "Value" ""
			(at 0 0 180)
			(layer "F.Fab")
			(effects
				(font
					(size 1.27 1.27)
				)
			)
		)
		(duplicate_pad_numbers_are_jumpers no)
		(fp_line
			(start 6.849872 6.450076)
			(end 6.849872 2.6416)
			(stroke
				(width 0.1524)
				(type default)
			)
			(layer "F.SilkS")
		)
		(fp_line
			(start 6.849872 -2.6416)
			(end 6.849872 -6.450076)
			(stroke
				(width 0.1524)
				(type default)
			)
			(layer "F.SilkS")
		)
		(fp_line
			(start 6.849872 -6.450076)
			(end -6.849872 -6.450076)
			(stroke
				(width 0.1524)
				(type default)
			)
			(layer "F.SilkS")
		)
		(fp_line
			(start -6.849872 6.450076)
			(end 6.849872 6.450076)
			(stroke
				(width 0.1524)
				(type default)
			)
			(layer "F.SilkS")
		)
		(fp_line
			(start -6.849872 2.6416)
			(end -6.849872 6.450076)
			(stroke
				(width 0.1524)
				(type default)
			)
			(layer "F.SilkS")
		)
		(fp_line
			(start -6.849872 -6.450076)
			(end -6.849872 -2.6416)
			(stroke
				(width 0.1524)
				(type default)
			)
			(layer "F.SilkS")
		)
		(fp_line
			(start 6.849872 6.450076)
			(end 6.849872 -6.450076)
			(stroke
				(width 0.1)
				(type default)
			)
			(layer "F.Fab")
		)
		(fp_line
			(start 6.849872 -6.450076)
			(end -6.849872 -6.450076)
			(stroke
				(width 0.1)
				(type default)
			)
			(layer "F.Fab")
		)
		(fp_line
			(start -6.849872 6.450076)
			(end 6.849872 6.450076)
			(stroke
				(width 0.1)
				(type default)
			)
			(layer "F.Fab")
		)
		(fp_line
			(start -6.849872 -6.450076)
			(end -6.849872 6.450076)
			(stroke
				(width 0.1)
				(type default)
			)
			(layer "F.Fab")
		)
		(pad "1" smd rect
			(at -5.407406 0 180)
			(size 2.9464 5.0038)
			(layers "F.Cu" "F.Mask" "F.Paste")
			(net "P52V_HS")
		)
		(pad "2" smd rect
			(at 5.407406 0 180)
			(size 2.9464 5.0038)
			(layers "F.Cu" "F.Mask" "F.Paste")
			(net "P52V_HS_FILTER")
		)
	)
	(footprint ""
		(layer "F.Cu")
		(at 90.678 -60.96)
		(property "Reference" "PC96"
			(at -1.397 -3.52933 0)
			(unlocked yes)
			(layer "F.SilkS")
			(effects
				(font
					(size 0.7874 0.5842)
					(thickness 0.1524)
				)
				(justify left)
			)
		)
		(property "Value" ""
			(at 0 0 0)
			(layer "F.Fab")
			(effects
				(font
					(size 1.27 1.27)
				)
			)
		)
		(duplicate_pad_numbers_are_jumpers no)
		(fp_line
			(start 5.2578 2.499868)
			(end -5.2578 2.499868)
			(stroke
				(width 0.1524)
				(type default)
			)
			(layer "F.SilkS")
		)
		(fp_circle
			(center 0 2.499868)
			(end 5.2578 2.499868)
			(stroke
				(width 0.1524)
				(type default)
			)
			(fill no)
			(layer "F.SilkS")
		)
		(fp_poly
			(pts
				(arc
					(start 5.2578 2.499868)
					(mid 0 7.757922)
					(end -5.2578 2.499868)
				)
			)
			(stroke
				(width 0)
				(type default)
			)
			(fill yes)
			(layer "F.SilkS")
		)
		(fp_circle
			(center 0 2.499868)
			(end 5.2578 2.499868)
			(stroke
				(width 0.1)
				(type default)
			)
			(fill no)
			(layer "F.Fab")
		)
		(pad "1" thru_hole rect
			(at 0 0 270)
			(size 1.524 1.524)
			(drill 1.016)
			(layers "*.Cu" "*.Mask")
			(remove_unused_layers no)
			(net "P12V_BRICK")
			(clearance 0)
			(padstack
				(mode front_inner_back)
				(layer "Inner"
					(shape circle)
					(size 1.524 1.524)
					(clearance 0)
				)
				(layer "B.Cu"
					(shape rect)
					(size 1.524 1.524)
					(clearance 0)
				)
			)
		)
		(pad "2" thru_hole circle
			(at 0 4.99999 270)
			(size 1.524 1.524)
			(drill 1.016)
			(layers "*.Cu" "*.Mask")
			(remove_unused_layers no)
			(net "GND")
			(clearance 0)
		)
	)
	(footprint ""
		(layer "F.Cu")
		(at 301.625 -121.4755)
		(property "Reference" "PR6963"
			(at 0 0 0)
			(layer "F.SilkS")
			(hide yes)
			(effects
				(font
					(size 1.27 1.27)
				)
			)
		)
		(property "Value" ""
			(at 0 0 0)
			(layer "F.Fab")
			(effects
				(font
					(size 1.27 1.27)
				)
			)
		)
		(duplicate_pad_numbers_are_jumpers no)
		(fp_line
			(start -1.2954 -0.5842)
			(end 1.2954 -0.5842)
			(stroke
				(width 0.1524)
				(type default)
			)
			(layer "F.SilkS")
		)
		(fp_line
			(start -1.2954 0.5842)
			(end -1.2954 -0.5842)
			(stroke
				(width 0.1524)
				(type default)
			)
			(layer "F.SilkS")
		)
		(fp_line
			(start 1.2954 -0.5842)
			(end 1.2954 0.5842)
			(stroke
				(width 0.1524)
				(type default)
			)
			(layer "F.SilkS")
		)
		(fp_line
			(start 1.2954 0.5842)
			(end -1.2954 0.5842)
			(stroke
				(width 0.1524)
				(type default)
			)
			(layer "F.SilkS")
		)
		(fp_line
			(start -1.1938 -0.406654)
			(end -0.8636 -0.406654)
			(stroke
				(width 0.1)
				(type default)
			)
			(layer "F.Fab")
		)
		(fp_line
			(start -1.1938 0.4064)
			(end -1.1938 -0.406654)
			(stroke
				(width 0.1)
				(type default)
			)
			(layer "F.Fab")
		)
		(fp_line
			(start -0.8636 -0.4572)
			(end 0.8636 -0.4572)
			(stroke
				(width 0.1)
				(type default)
			)
			(layer "F.Fab")
		)
		(fp_line
			(start -0.8636 -0.406654)
			(end -0.8636 -0.4572)
			(stroke
				(width 0.1)
				(type default)
			)
			(layer "F.Fab")
		)
		(fp_line
			(start -0.8636 0.4064)
			(end -1.1938 0.4064)
			(stroke
				(width 0.1)
				(type default)
			)
			(layer "F.Fab")
		)
		(fp_line
			(start -0.8636 0.4318)
			(end -0.8636 0.4064)
			(stroke
				(width 0.1)
				(type default)
			)
			(layer "F.Fab")
		)
		(fp_line
			(start -0.8636 0.4572)
			(end -0.8636 0.4318)
			(stroke
				(width 0.1)
				(type default)
			)
			(layer "F.Fab")
		)
		(fp_line
			(start 0.8636 -0.4572)
			(end 0.8636 -0.406654)
			(stroke
				(width 0.1)
				(type default)
			)
			(layer "F.Fab")
		)
		(fp_line
			(start 0.8636 -0.406654)
			(end 1.1938 -0.406654)
			(stroke
				(width 0.1)
				(type default)
			)
			(layer "F.Fab")
		)
		(fp_line
			(start 0.8636 0.4064)
			(end 0.8636 0.4572)
			(stroke
				(width 0.1)
				(type default)
			)
			(layer "F.Fab")
		)
		(fp_line
			(start 0.8636 0.4572)
			(end -0.8636 0.4572)
			(stroke
				(width 0.1)
				(type default)
			)
			(layer "F.Fab")
		)
		(fp_line
			(start 1.1938 -0.406654)
			(end 1.1938 0.4064)
			(stroke
				(width 0.1)
				(type default)
			)
			(layer "F.Fab")
		)
		(fp_line
			(start 1.1938 0.4064)
			(end 0.8636 0.4064)
			(stroke
				(width 0.1)
				(type default)
			)
			(layer "F.Fab")
		)
		(pad "1" smd rect
			(at -0.7366 0 270)
			(size 0.7112 0.8128)
			(layers "F.Cu" "F.Mask" "F.Paste")
			(net "P52V_HS_4287_ADC_P")
		)
		(pad "2" smd rect
			(at 0.7366 0 270)
			(size 0.7112 0.8128)
			(layers "F.Cu" "F.Mask" "F.Paste")
			(net "P52V_HS1_SENSE_P_R1")
		)
	)
	(footprint ""
		(layer "F.Cu")
		(at 179.06746 -49.911)
		(property "Reference" "PC132"
			(at 0 0 0)
			(layer "F.SilkS")
			(hide yes)
			(effects
				(font
					(size 1.27 1.27)
				)
			)
		)
		(property "Value" ""
			(at 0 0 0)
			(layer "F.Fab")
			(effects
				(font
					(size 1.27 1.27)
				)
			)
		)
		(duplicate_pad_numbers_are_jumpers no)
		(fp_line
			(start -1.524 -0.762)
			(end 1.524 -0.762)
			(stroke
				(width 0.1524)
				(type default)
			)
			(layer "F.SilkS")
		)
		(fp_line
			(start -1.524 0.762)
			(end -1.524 -0.762)
			(stroke
				(width 0.1524)
				(type default)
			)
			(layer "F.SilkS")
		)
		(fp_line
			(start 1.524 -0.762)
			(end 1.524 0.762)
			(stroke
				(width 0.1524)
				(type default)
			)
			(layer "F.SilkS")
		)
		(fp_line
			(start 1.524 0.762)
			(end -1.524 0.762)
			(stroke
				(width 0.1524)
				(type default)
			)
			(layer "F.SilkS")
		)
		(fp_line
			(start -1.1049 -0.724916)
			(end -1.1049 0.724916)
			(stroke
				(width 0.1)
				(type default)
			)
			(layer "F.Fab")
		)
		(fp_line
			(start -1.1049 0.724916)
			(end 1.1049 0.724916)
			(stroke
				(width 0.1)
				(type default)
			)
			(layer "F.Fab")
		)
		(fp_line
			(start 1.1049 -0.724916)
			(end -1.1049 -0.724916)
			(stroke
				(width 0.1)
				(type default)
			)
			(layer "F.Fab")
		)
		(fp_line
			(start 1.1049 0.724916)
			(end 1.1049 -0.724916)
			(stroke
				(width 0.1)
				(type default)
			)
			(layer "F.Fab")
		)
		(pad "1" smd rect
			(at -0.889 0 180)
			(size 1.016 1.27)
			(layers "F.Cu" "F.Mask" "F.Paste")
			(net "P12V_BRICK")
		)
		(pad "2" smd rect
			(at 0.889 0 180)
			(size 1.016 1.27)
			(layers "F.Cu" "F.Mask" "F.Paste")
			(net "GND")
		)
	)
	(footprint ""
		(layer "F.Cu")
		(at 189.098174 -127.889)
		(property "Reference" "PC119"
			(at 0 0 0)
			(layer "F.SilkS")
			(hide yes)
			(effects
				(font
					(size 1.27 1.27)
				)
			)
		)
		(property "Value" ""
			(at 0 0 0)
			(layer "F.Fab")
			(effects
				(font
					(size 1.27 1.27)
				)
			)
		)
		(duplicate_pad_numbers_are_jumpers no)
		(fp_line
			(start -2.2098 -0.9398)
			(end 2.2098 -0.9398)
			(stroke
				(width 0.1524)
				(type default)
			)
			(layer "F.SilkS")
		)
		(fp_line
			(start -2.2098 0.9398)
			(end -2.2098 -0.9398)
			(stroke
				(width 0.1524)
				(type default)
			)
			(layer "F.SilkS")
		)
		(fp_line
			(start 2.2098 -0.9398)
			(end 2.2098 0.9398)
			(stroke
				(width 0.1524)
				(type default)
			)
			(layer "F.SilkS")
		)
		(fp_line
			(start 2.2098 0.9398)
			(end -2.2098 0.9398)
			(stroke
				(width 0.1524)
				(type default)
			)
			(layer "F.SilkS")
		)
		(fp_line
			(start -1.700022 -0.899922)
			(end 1.700022 -0.899922)
			(stroke
				(width 0.1)
				(type default)
			)
			(layer "F.Fab")
		)
		(fp_line
			(start -1.700022 0.899922)
			(end -1.700022 -0.899922)
			(stroke
				(width 0.1)
				(type default)
			)
			(layer "F.Fab")
		)
		(fp_line
			(start 1.700022 -0.899922)
			(end 1.700022 0.899922)
			(stroke
				(width 0.1)
				(type default)
			)
			(layer "F.Fab")
		)
		(fp_line
			(start 1.700022 0.899922)
			(end -1.700022 0.899922)
			(stroke
				(width 0.1)
				(type default)
			)
			(layer "F.Fab")
		)
		(pad "1" smd rect
			(at -1.4732 0 180)
			(size 1.1684 1.5748)
			(layers "F.Cu" "F.Mask" "F.Paste")
			(net "P52V_HS_FILTER")
		)
		(pad "2" smd rect
			(at 1.4732 0 180)
			(size 1.1684 1.5748)
			(layers "F.Cu" "F.Mask" "F.Paste")
			(net "GND")
		)
	)
	(footprint ""
		(layer "F.Cu")
		(at 236.982 -95.504 -90)
		(property "Reference" "C41"
			(at 0 0 270)
			(layer "F.SilkS")
			(hide yes)
			(effects
				(font
					(size 1.27 1.27)
				)
			)
		)
		(property "Value" ""
			(at 0 0 270)
			(layer "F.Fab")
			(effects
				(font
					(size 1.27 1.27)
				)
			)
		)
		(duplicate_pad_numbers_are_jumpers no)
		(fp_line
			(start -2.2098 0.9398)
			(end -2.2098 -0.9398)
			(stroke
				(width 0.1524)
				(type default)
			)
			(layer "F.SilkS")
		)
		(fp_line
			(start 2.2098 0.9398)
			(end -2.2098 0.9398)
			(stroke
				(width 0.1524)
				(type default)
			)
			(layer "F.SilkS")
		)
		(fp_line
			(start -2.2098 -0.9398)
			(end 2.2098 -0.9398)
			(stroke
				(width 0.1524)
				(type default)
			)
			(layer "F.SilkS")
		)
		(fp_line
			(start 2.2098 -0.9398)
			(end 2.2098 0.9398)
			(stroke
				(width 0.1524)
				(type default)
			)
			(layer "F.SilkS")
		)
		(fp_line
			(start -1.700022 0.899922)
			(end -1.700022 -0.899922)
			(stroke
				(width 0.1)
				(type default)
			)
			(layer "F.Fab")
		)
		(fp_line
			(start 1.700022 0.899922)
			(end -1.700022 0.899922)
			(stroke
				(width 0.1)
				(type default)
			)
			(layer "F.Fab")
		)
		(fp_line
			(start -1.700022 -0.899922)
			(end 1.700022 -0.899922)
			(stroke
				(width 0.1)
				(type default)
			)
			(layer "F.Fab")
		)
		(fp_line
			(start 1.700022 -0.899922)
			(end 1.700022 0.899922)
			(stroke
				(width 0.1)
				(type default)
			)
			(layer "F.Fab")
		)
		(pad "1" smd rect
			(at -1.4732 0 90)
			(size 1.1684 1.5748)
			(layers "F.Cu" "F.Mask" "F.Paste")
			(net "P52V_HS")
		)
		(pad "2" smd rect
			(at 1.4732 0 90)
			(size 1.1684 1.5748)
			(layers "F.Cu" "F.Mask" "F.Paste")
			(net "GND")
		)
	)
)
